(kicad_pcb
	(version 20260206)
	(generator "pcbnew")
	(generator_version "10.0")
	(general
		(thickness 1.6)
		(legacy_teardrops no)
	)
	(paper "A4")
	(title_block
		(title "baseboard — 13948-1b.1110WZS1818.brd")
		(comment 1 "Honey Badger (Wiwynn) / footprints 1929-1935 of 2523")
	)
	(layers
		(0 "F.Cu" signal "TOP")
		(4 "In1.Cu" signal "L2GND")
		(6 "In2.Cu" signal "L3")
		(8 "In3.Cu" signal "L4VCC")
		(10 "In4.Cu" signal "L5VCC")
		(12 "In5.Cu" signal "L6")
		(14 "In6.Cu" signal "L7GND")
		(2 "B.Cu" signal "BOTTOM")
		(9 "F.Adhes" user "F.Adhesive")
		(11 "B.Adhes" user "B.Adhesive")
		(13 "F.Paste" user "Package Geometry/Pastemask Top")
		(15 "B.Paste" user "Package Geometry/Pastemask Bottom")
		(5 "F.SilkS" user "Ref Des/Silkscreen Top")
		(7 "B.SilkS" user "Ref Des/Silkscreen Bottom")
		(1 "F.Mask" user "Board Geometry/Soldermask Top")
		(3 "B.Mask" user "Board Geometry/Soldermask Bottom")
		(17 "Dwgs.User" user "User.Drawings")
		(19 "Cmts.User" user "User.Comments")
		(21 "Eco1.User" user "User.Eco1")
		(23 "Eco2.User" user "User.Eco2")
		(25 "Edge.Cuts" user "Board Geometry/Outline")
		(27 "Margin" user)
		(31 "F.CrtYd" user "Package Geometry/Place Bound Top")
		(29 "B.CrtYd" user "Package Geometry/Place Bound Bottom")
		(35 "F.Fab" user "Ref Des/Assembly Top")
		(33 "B.Fab" user "Ref Des/Assembly Bottom")
	)
	(footprint ""
		(layer "B.Cu")
		(at 351.663 -81.534 180)
		(property "Reference" "R266"
			(at 0 0 0)
			(layer "B.SilkS")
			(hide yes)
			(effects
				(font
					(size 1.27 1.27)
				)
				(justify mirror)
			)
		)
		(property "Value" "2K2R2J-2-GP"
			(at -0.064008 -3.993896 180)
			(unlocked yes)
			(layer "B.Fab")
			(hide yes)
			(effects
				(font
					(size 1.016 1.016)
					(thickness 0.1524)
				)
				(justify mirror)
			)
		)
		(property "Device Type" "R402H16"
			(at -0.064008 -5.517896 180)
			(unlocked yes)
			(layer "B.Fab")
			(hide yes)
			(effects
				(font
					(size 1.016 1.016)
					(thickness 0.1524)
				)
				(justify mirror)
			)
		)
		(duplicate_pad_numbers_are_jumpers no)
		(fp_line
			(start 0.508 -0.9398)
			(end 0.508 0.9398)
			(stroke
				(width 0.1524)
				(type default)
			)
			(layer "B.SilkS")
		)
		(fp_line
			(start -0.508 -0.9398)
			(end 0.508 -0.9398)
			(stroke
				(width 0.1524)
				(type default)
			)
			(layer "B.SilkS")
		)
		(fp_rect
			(start 0.508 0.9398)
			(end -0.508 -0.9398)
			(stroke
				(width 0)
				(type default)
			)
			(fill no)
			(layer "B.CrtYd")
		)
		(fp_rect
			(start 0.508 0.9398)
			(end -0.508 -0.9398)
			(stroke
				(width 0)
				(type default)
			)
			(fill no)
			(layer "B.Fab")
		)
		(pad "1" smd custom
			(at 0 -0.4445)
			(size 0.1397 0.1397)
			(layers "B.Cu" "B.Mask" "B.Paste")
			(net "P3V3_STBY")
			(options
				(clearance outline)
				(anchor circle)
			)
			(primitives
				(gr_poly
					(pts
						(arc
							(start -0.1778 0.2794)
							(mid -0.249642 0.249642)
							(end -0.2794 0.1778)
						)
						(arc
							(start -0.2794 -0.1778)
							(mid -0.249642 -0.249642)
							(end -0.1778 -0.2794)
						)
						(arc
							(start 0.1778 -0.2794)
							(mid 0.249642 -0.249642)
							(end 0.2794 -0.1778)
						)
						(arc
							(start 0.2794 0.1778)
							(mid 0.249642 0.249642)
							(end 0.1778 0.2794)
						)
					)
					(width 0)
					(fill yes)
				)
			)
		)
		(pad "2" smd custom
			(at 0 0.4445)
			(size 0.1397 0.1397)
			(layers "B.Cu" "B.Mask" "B.Paste")
			(net "PU_IBMC_BT_HOLD_N")
			(options
				(clearance outline)
				(anchor circle)
			)
			(primitives
				(gr_poly
					(pts
						(arc
							(start -0.1778 0.2794)
							(mid -0.249642 0.249642)
							(end -0.2794 0.1778)
						)
						(arc
							(start -0.2794 -0.1778)
							(mid -0.249642 -0.249642)
							(end -0.1778 -0.2794)
						)
						(arc
							(start 0.1778 -0.2794)
							(mid 0.249642 -0.249642)
							(end 0.2794 -0.1778)
						)
						(arc
							(start 0.2794 0.1778)
							(mid 0.249642 0.249642)
							(end 0.1778 0.2794)
						)
					)
					(width 0)
					(fill yes)
				)
			)
		)
	)
	(footprint ""
		(layer "B.Cu")
		(at 309.118 -50.927 180)
		(property "Reference" "C277"
			(at 0 0 0)
			(layer "B.SilkS")
			(hide yes)
			(effects
				(font
					(size 1.27 1.27)
				)
				(justify mirror)
			)
		)
		(property "Value" "SCD1U25V2KX-2-GP"
			(at -1.1811 -2.7051 180)
			(unlocked yes)
			(layer "B.Fab")
			(hide yes)
			(effects
				(font
					(size 1.016 1.016)
					(thickness 0.1524)
				)
				(justify mirror)
			)
		)
		(property "Device Type" "C402H22"
			(at -1.1811 -4.2291 180)
			(unlocked yes)
			(layer "B.Fab")
			(hide yes)
			(effects
				(font
					(size 1.016 1.016)
					(thickness 0.1524)
				)
				(justify mirror)
			)
		)
		(duplicate_pad_numbers_are_jumpers no)
		(fp_rect
			(start 0.4318 0.9525)
			(end -0.4318 -0.9525)
			(stroke
				(width 0)
				(type default)
			)
			(fill no)
			(layer "B.CrtYd")
		)
		(fp_rect
			(start 0.4318 0.9525)
			(end -0.4318 -0.9525)
			(stroke
				(width 0)
				(type default)
			)
			(fill no)
			(layer "B.Fab")
		)
		(pad "1" smd custom
			(at 0 -0.4445)
			(size 0.1524 0.1524)
			(layers "B.Cu" "B.Mask" "B.Paste")
			(net "P12V")
			(options
				(clearance outline)
				(anchor circle)
			)
			(primitives
				(gr_poly
					(pts
						(arc
							(start 0.3048 0.2032)
							(mid 0.275042 0.275042)
							(end 0.2032 0.3048)
						)
						(arc
							(start -0.2032 0.3048)
							(mid -0.275042 0.275042)
							(end -0.3048 0.2032)
						)
						(arc
							(start -0.3048 -0.2032)
							(mid -0.275042 -0.275042)
							(end -0.2032 -0.3048)
						)
						(arc
							(start 0.2032 -0.3048)
							(mid 0.275042 -0.275042)
							(end 0.3048 -0.2032)
						)
					)
					(width 0)
					(fill yes)
				)
			)
		)
		(pad "2" smd custom
			(at 0 0.4445)
			(size 0.1524 0.1524)
			(layers "B.Cu" "B.Mask" "B.Paste")
			(net "GND")
			(options
				(clearance outline)
				(anchor circle)
			)
			(primitives
				(gr_poly
					(pts
						(arc
							(start 0.3048 0.2032)
							(mid 0.275042 0.275042)
							(end 0.2032 0.3048)
						)
						(arc
							(start -0.2032 0.3048)
							(mid -0.275042 0.275042)
							(end -0.3048 0.2032)
						)
						(arc
							(start -0.3048 -0.2032)
							(mid -0.275042 -0.275042)
							(end -0.2032 -0.3048)
						)
						(arc
							(start 0.2032 -0.3048)
							(mid 0.275042 -0.275042)
							(end 0.3048 -0.2032)
						)
					)
					(width 0)
					(fill yes)
				)
			)
		)
	)
	(footprint ""
		(layer "B.Cu")
		(at 12.19708 -231.822752)
		(property "Reference" "R513"
			(at 0 0 0)
			(layer "B.SilkS")
			(hide yes)
			(effects
				(font
					(size 1.27 1.27)
				)
				(justify mirror)
			)
		)
		(property "Value" "0R2J-2-GP"
			(at -0.064008 -3.993896 0)
			(unlocked yes)
			(layer "B.Fab")
			(hide yes)
			(effects
				(font
					(size 1.016 1.016)
					(thickness 0.1524)
				)
				(justify mirror)
			)
		)
		(property "Device Type" "R402H16"
			(at -0.064008 -5.517896 0)
			(unlocked yes)
			(layer "B.Fab")
			(hide yes)
			(effects
				(font
					(size 1.016 1.016)
					(thickness 0.1524)
				)
				(justify mirror)
			)
		)
		(duplicate_pad_numbers_are_jumpers no)
		(fp_line
			(start -0.508 -0.9398)
			(end 0.508 -0.9398)
			(stroke
				(width 0.1524)
				(type default)
			)
			(layer "B.SilkS")
		)
		(fp_line
			(start 0.508 -0.9398)
			(end 0.508 0.9398)
			(stroke
				(width 0.1524)
				(type default)
			)
			(layer "B.SilkS")
		)
		(fp_rect
			(start 0.508 0.9398)
			(end -0.508 -0.9398)
			(stroke
				(width 0)
				(type default)
			)
			(fill no)
			(layer "B.CrtYd")
		)
		(fp_rect
			(start 0.508 0.9398)
			(end -0.508 -0.9398)
			(stroke
				(width 0)
				(type default)
			)
			(fill no)
			(layer "B.Fab")
		)
		(pad "1" smd custom
			(at 0 -0.4445 180)
			(size 0.1397 0.1397)
			(layers "B.Cu" "B.Mask" "B.Paste")
			(net "SAS_HDD_PWR11_PCIE")
			(options
				(clearance outline)
				(anchor circle)
			)
			(primitives
				(gr_poly
					(pts
						(arc
							(start -0.1778 0.2794)
							(mid -0.249642 0.249642)
							(end -0.2794 0.1778)
						)
						(arc
							(start -0.2794 -0.1778)
							(mid -0.249642 -0.249642)
							(end -0.1778 -0.2794)
						)
						(arc
							(start 0.1778 -0.2794)
							(mid 0.249642 -0.249642)
							(end 0.2794 -0.1778)
						)
						(arc
							(start 0.2794 0.1778)
							(mid 0.249642 0.249642)
							(end 0.1778 0.2794)
						)
					)
					(width 0)
					(fill yes)
				)
			)
		)
		(pad "2" smd custom
			(at 0 0.4445 180)
			(size 0.1397 0.1397)
			(layers "B.Cu" "B.Mask" "B.Paste")
			(net "SAS_HDD_PWR11")
			(options
				(clearance outline)
				(anchor circle)
			)
			(primitives
				(gr_poly
					(pts
						(arc
							(start -0.1778 0.2794)
							(mid -0.249642 0.249642)
							(end -0.2794 0.1778)
						)
						(arc
							(start -0.2794 -0.1778)
							(mid -0.249642 -0.249642)
							(end -0.1778 -0.2794)
						)
						(arc
							(start 0.1778 -0.2794)
							(mid 0.249642 -0.249642)
							(end 0.2794 -0.1778)
						)
						(arc
							(start 0.2794 0.1778)
							(mid 0.249642 0.249642)
							(end 0.1778 0.2794)
						)
					)
					(width 0)
					(fill yes)
				)
			)
		)
	)
	(footprint ""
		(layer "B.Cu")
		(at 119.996966 -38.989 -90)
		(property "Reference" "SR621"
			(at 0 0 90)
			(layer "B.SilkS")
			(hide yes)
			(effects
				(font
					(size 1.27 1.27)
				)
				(justify mirror)
			)
		)
		(property "Value" "2K2R2F-GP"
			(at -0.064008 -3.993896 270)
			(unlocked yes)
			(layer "B.Fab")
			(hide yes)
			(effects
				(font
					(size 1.016 1.016)
					(thickness 0.1524)
				)
				(justify mirror)
			)
		)
		(property "Device Type" "R402H16"
			(at -0.064008 -5.517896 270)
			(unlocked yes)
			(layer "B.Fab")
			(hide yes)
			(effects
				(font
					(size 1.016 1.016)
					(thickness 0.1524)
				)
				(justify mirror)
			)
		)
		(duplicate_pad_numbers_are_jumpers no)
		(fp_line
			(start -0.508 -0.9398)
			(end 0.508 -0.9398)
			(stroke
				(width 0.1524)
				(type default)
			)
			(layer "B.SilkS")
		)
		(fp_line
			(start 0.508 -0.9398)
			(end 0.508 0.9398)
			(stroke
				(width 0.1524)
				(type default)
			)
			(layer "B.SilkS")
		)
		(fp_rect
			(start 0.508 0.9398)
			(end -0.508 -0.9398)
			(stroke
				(width 0)
				(type default)
			)
			(fill no)
			(layer "B.CrtYd")
		)
		(fp_rect
			(start 0.508 0.9398)
			(end -0.508 -0.9398)
			(stroke
				(width 0)
				(type default)
			)
			(fill no)
			(layer "B.Fab")
		)
		(pad "1" smd custom
			(at 0 -0.4445 90)
			(size 0.1397 0.1397)
			(layers "B.Cu" "B.Mask" "B.Paste")
			(net "P1V8_C")
			(options
				(clearance outline)
				(anchor circle)
			)
			(primitives
				(gr_poly
					(pts
						(arc
							(start -0.1778 0.2794)
							(mid -0.249642 0.249642)
							(end -0.2794 0.1778)
						)
						(arc
							(start -0.2794 -0.1778)
							(mid -0.249642 -0.249642)
							(end -0.1778 -0.2794)
						)
						(arc
							(start 0.1778 -0.2794)
							(mid 0.249642 -0.249642)
							(end 0.2794 -0.1778)
						)
						(arc
							(start 0.2794 0.1778)
							(mid 0.249642 0.249642)
							(end 0.1778 0.2794)
						)
					)
					(width 0)
					(fill yes)
				)
			)
		)
		(pad "2" smd custom
			(at 0 0.4445 90)
			(size 0.1397 0.1397)
			(layers "B.Cu" "B.Mask" "B.Paste")
			(net "IOC_SDA_2")
			(options
				(clearance outline)
				(anchor circle)
			)
			(primitives
				(gr_poly
					(pts
						(arc
							(start -0.1778 0.2794)
							(mid -0.249642 0.249642)
							(end -0.2794 0.1778)
						)
						(arc
							(start -0.2794 -0.1778)
							(mid -0.249642 -0.249642)
							(end -0.1778 -0.2794)
						)
						(arc
							(start 0.1778 -0.2794)
							(mid 0.249642 -0.249642)
							(end 0.2794 -0.1778)
						)
						(arc
							(start 0.2794 0.1778)
							(mid 0.249642 0.249642)
							(end 0.1778 0.2794)
						)
					)
					(width 0)
					(fill yes)
				)
			)
		)
	)
	(footprint ""
		(layer "B.Cu")
		(at 344.551 -115.824 -90)
		(property "Reference" "PC19"
			(at 0 0 90)
			(layer "B.SilkS")
			(hide yes)
			(effects
				(font
					(size 1.27 1.27)
				)
				(justify mirror)
			)
		)
		(property "Value" "SC1KP50V2KX-1GP"
			(at -1.1811 -2.7051 270)
			(unlocked yes)
			(layer "B.Fab")
			(hide yes)
			(effects
				(font
					(size 1.016 1.016)
					(thickness 0.1524)
				)
				(justify mirror)
			)
		)
		(property "Device Type" "C402H22"
			(at -1.1811 -4.2291 270)
			(unlocked yes)
			(layer "B.Fab")
			(hide yes)
			(effects
				(font
					(size 1.016 1.016)
					(thickness 0.1524)
				)
				(justify mirror)
			)
		)
		(duplicate_pad_numbers_are_jumpers no)
		(fp_rect
			(start 0.4318 0.9525)
			(end -0.4318 -0.9525)
			(stroke
				(width 0)
				(type default)
			)
			(fill no)
			(layer "B.CrtYd")
		)
		(fp_rect
			(start 0.4318 0.9525)
			(end -0.4318 -0.9525)
			(stroke
				(width 0)
				(type default)
			)
			(fill no)
			(layer "B.Fab")
		)
		(pad "1" smd custom
			(at 0 -0.4445 90)
			(size 0.1524 0.1524)
			(layers "B.Cu" "B.Mask" "B.Paste")
			(net "P5V_STBY_VFB_R")
			(options
				(clearance outline)
				(anchor circle)
			)
			(primitives
				(gr_poly
					(pts
						(arc
							(start 0.3048 0.2032)
							(mid 0.275042 0.275042)
							(end 0.2032 0.3048)
						)
						(arc
							(start -0.2032 0.3048)
							(mid -0.275042 0.275042)
							(end -0.3048 0.2032)
						)
						(arc
							(start -0.3048 -0.2032)
							(mid -0.275042 -0.275042)
							(end -0.2032 -0.3048)
						)
						(arc
							(start 0.2032 -0.3048)
							(mid 0.275042 -0.275042)
							(end 0.3048 -0.2032)
						)
					)
					(width 0)
					(fill yes)
				)
			)
		)
		(pad "2" smd custom
			(at 0 0.4445 90)
			(size 0.1524 0.1524)
			(layers "B.Cu" "B.Mask" "B.Paste")
			(net "P5V_STBY_VFB")
			(options
				(clearance outline)
				(anchor circle)
			)
			(primitives
				(gr_poly
					(pts
						(arc
							(start 0.3048 0.2032)
							(mid 0.275042 0.275042)
							(end 0.2032 0.3048)
						)
						(arc
							(start -0.2032 0.3048)
							(mid -0.275042 0.275042)
							(end -0.3048 0.2032)
						)
						(arc
							(start -0.3048 -0.2032)
							(mid -0.275042 -0.275042)
							(end -0.2032 -0.3048)
						)
						(arc
							(start 0.2032 -0.3048)
							(mid 0.275042 -0.275042)
							(end 0.3048 -0.2032)
						)
					)
					(width 0)
					(fill yes)
				)
			)
		)
	)
	(footprint ""
		(layer "B.Cu")
		(at 86.614 -29.09316 180)
		(property "Reference" "SR585"
			(at 0 0 0)
			(layer "B.SilkS")
			(hide yes)
			(effects
				(font
					(size 1.27 1.27)
				)
				(justify mirror)
			)
		)
		(property "Value" "51R2F-2-GP"
			(at -0.064008 -3.993896 180)
			(unlocked yes)
			(layer "B.Fab")
			(hide yes)
			(effects
				(font
					(size 1.016 1.016)
					(thickness 0.1524)
				)
				(justify mirror)
			)
		)
		(property "Device Type" "R402H16"
			(at -0.064008 -5.517896 180)
			(unlocked yes)
			(layer "B.Fab")
			(hide yes)
			(effects
				(font
					(size 1.016 1.016)
					(thickness 0.1524)
				)
				(justify mirror)
			)
		)
		(duplicate_pad_numbers_are_jumpers no)
		(fp_line
			(start 0.508 -0.9398)
			(end 0.508 0.9398)
			(stroke
				(width 0.1524)
				(type default)
			)
			(layer "B.SilkS")
		)
		(fp_line
			(start -0.508 -0.9398)
			(end 0.508 -0.9398)
			(stroke
				(width 0.1524)
				(type default)
			)
			(layer "B.SilkS")
		)
		(fp_rect
			(start 0.508 0.9398)
			(end -0.508 -0.9398)
			(stroke
				(width 0)
				(type default)
			)
			(fill no)
			(layer "B.CrtYd")
		)
		(fp_rect
			(start 0.508 0.9398)
			(end -0.508 -0.9398)
			(stroke
				(width 0)
				(type default)
			)
			(fill no)
			(layer "B.Fab")
		)
		(pad "1" smd custom
			(at 0 -0.4445)
			(size 0.1397 0.1397)
			(layers "B.Cu" "B.Mask" "B.Paste")
			(net "GND")
			(options
				(clearance outline)
				(anchor circle)
			)
			(primitives
				(gr_poly
					(pts
						(arc
							(start -0.1778 0.2794)
							(mid -0.249642 0.249642)
							(end -0.2794 0.1778)
						)
						(arc
							(start -0.2794 -0.1778)
							(mid -0.249642 -0.249642)
							(end -0.1778 -0.2794)
						)
						(arc
							(start 0.1778 -0.2794)
							(mid 0.249642 -0.249642)
							(end 0.2794 -0.1778)
						)
						(arc
							(start 0.2794 0.1778)
							(mid 0.249642 0.249642)
							(end 0.1778 0.2794)
						)
					)
					(width 0)
					(fill yes)
				)
			)
		)
		(pad "2" smd custom
			(at 0 0.4445)
			(size 0.1397 0.1397)
			(layers "B.Cu" "B.Mask" "B.Paste")
			(net "CK_100M_EXP_SAS")
			(options
				(clearance outline)
				(anchor circle)
			)
			(primitives
				(gr_poly
					(pts
						(arc
							(start -0.1778 0.2794)
							(mid -0.249642 0.249642)
							(end -0.2794 0.1778)
						)
						(arc
							(start -0.2794 -0.1778)
							(mid -0.249642 -0.249642)
							(end -0.1778 -0.2794)
						)
						(arc
							(start 0.1778 -0.2794)
							(mid 0.249642 -0.249642)
							(end 0.2794 -0.1778)
						)
						(arc
							(start 0.2794 0.1778)
							(mid 0.249642 0.249642)
							(end 0.1778 0.2794)
						)
					)
					(width 0)
					(fill yes)
				)
			)
		)
	)
	(footprint ""
		(layer "B.Cu")
		(at 101.454966 -44.958 -90)
		(property "Reference" "SC1025"
			(at 0 0 90)
			(layer "B.SilkS")
			(hide yes)
			(effects
				(font
					(size 1.27 1.27)
				)
				(justify mirror)
			)
		)
		(property "Value" "SC1U10V2KX-4-GP"
			(at -1.1811 -2.7051 270)
			(unlocked yes)
			(layer "B.Fab")
			(hide yes)
			(effects
				(font
					(size 1.016 1.016)
					(thickness 0.1524)
				)
				(justify mirror)
			)
		)
		(property "Device Type" "C402H22"
			(at -1.1811 -4.2291 270)
			(unlocked yes)
			(layer "B.Fab")
			(hide yes)
			(effects
				(font
					(size 1.016 1.016)
					(thickness 0.1524)
				)
				(justify mirror)
			)
		)
		(duplicate_pad_numbers_are_jumpers no)
		(fp_rect
			(start 0.4318 0.9525)
			(end -0.4318 -0.9525)
			(stroke
				(width 0)
				(type default)
			)
			(fill no)
			(layer "B.CrtYd")
		)
		(fp_rect
			(start 0.4318 0.9525)
			(end -0.4318 -0.9525)
			(stroke
				(width 0)
				(type default)
			)
			(fill no)
			(layer "B.Fab")
		)
		(pad "1" smd custom
			(at 0 -0.4445 90)
			(size 0.1524 0.1524)
			(layers "B.Cu" "B.Mask" "B.Paste")
			(net "P0V955_C")
			(options
				(clearance outline)
				(anchor circle)
			)
			(primitives
				(gr_poly
					(pts
						(arc
							(start 0.3048 0.2032)
							(mid 0.275042 0.275042)
							(end 0.2032 0.3048)
						)
						(arc
							(start -0.2032 0.3048)
							(mid -0.275042 0.275042)
							(end -0.3048 0.2032)
						)
						(arc
							(start -0.3048 -0.2032)
							(mid -0.275042 -0.275042)
							(end -0.2032 -0.3048)
						)
						(arc
							(start 0.2032 -0.3048)
							(mid 0.275042 -0.275042)
							(end 0.3048 -0.2032)
						)
					)
					(width 0)
					(fill yes)
				)
			)
		)
		(pad "2" smd custom
			(at 0 0.4445 90)
			(size 0.1524 0.1524)
			(layers "B.Cu" "B.Mask" "B.Paste")
			(net "GND")
			(options
				(clearance outline)
				(anchor circle)
			)
			(primitives
				(gr_poly
					(pts
						(arc
							(start 0.3048 0.2032)
							(mid 0.275042 0.275042)
							(end 0.2032 0.3048)
						)
						(arc
							(start -0.2032 0.3048)
							(mid -0.275042 0.275042)
							(end -0.3048 0.2032)
						)
						(arc
							(start -0.3048 -0.2032)
							(mid -0.275042 -0.275042)
							(end -0.2032 -0.3048)
						)
						(arc
							(start 0.2032 -0.3048)
							(mid 0.275042 -0.275042)
							(end 0.3048 -0.2032)
						)
					)
					(width 0)
					(fill yes)
				)
			)
		)
	)
)
